(kicad_pcb
	(version 20260206)
	(generator "pcbnew")
	(generator_version "10.0")
	(general
		(thickness 1.6)
		(legacy_teardrops no)
	)
	(paper "A4")
	(title_block
		(title "Wiwynn_Tioga_Pass_MB.brd")
		(comment 1 "Tioga Pass / footprints 2179-2184 of 4770")
	)
	(layers
		(0 "F.Cu" signal "TOP")
		(4 "In1.Cu" signal "L2GND")
		(6 "In2.Cu" signal "L3")
		(8 "In3.Cu" signal "L4GND")
		(10 "In4.Cu" signal "L5")
		(12 "In5.Cu" signal "L6GND")
		(14 "In6.Cu" signal "L7VCC")
		(16 "In7.Cu" signal "L8VCC")
		(18 "In8.Cu" signal "L9GND")
		(20 "In9.Cu" signal "L10")
		(22 "In10.Cu" signal "L11GND")
		(24 "In11.Cu" signal "L12")
		(26 "In12.Cu" signal "L13GND")
		(2 "B.Cu" signal "BOTTOM")
		(9 "F.Adhes" user "F.Adhesive")
		(11 "B.Adhes" user "B.Adhesive")
		(13 "F.Paste" user "Package Geometry/Pastemask Top")
		(15 "B.Paste" user "Package Geometry/Pastemask Bottom")
		(5 "F.SilkS" user "Ref Des/Silkscreen Top")
		(7 "B.SilkS" user "Ref Des/Silkscreen Bottom")
		(1 "F.Mask" user "Board Geometry/Soldermask Top")
		(3 "B.Mask" user "Board Geometry/Soldermask Bottom")
		(17 "Dwgs.User" user "User.Drawings")
		(19 "Cmts.User" user "User.Comments")
		(21 "Eco1.User" user "User.Eco1")
		(23 "Eco2.User" user "User.Eco2")
		(25 "Edge.Cuts" user "Board Geometry/Outline")
		(27 "Margin" user)
		(31 "F.CrtYd" user "Package Geometry/Place Bound Top")
		(29 "B.CrtYd" user "Package Geometry/Place Bound Bottom")
		(35 "F.Fab" user "Ref Des/Assembly Top")
		(33 "B.Fab" user "Ref Des/Assembly Bottom")
	)
	(footprint ""
		(layer "F.Cu")
		(at 101.3968 -3.3528 90)
		(property "Reference" "C2G13"
			(at 1.848866 0.752348 90)
			(unlocked yes)
			(layer "F.SilkS")
			(effects
				(font
					(size 1.27 0.9652)
					(thickness 0.1524)
				)
			)
		)
		(property "Value" ""
			(at 0 0 90)
			(layer "F.Fab")
			(effects
				(font
					(size 1.27 1.27)
				)
			)
		)
		(duplicate_pad_numbers_are_jumpers no)
		(fp_rect
			(start -0.500126 1.598422)
			(end 0.500126 -0.201422)
			(stroke
				(width 0)
				(type default)
			)
			(fill no)
			(layer "F.CrtYd")
		)
		(fp_line
			(start 0.500126 -0.201422)
			(end 0.500126 1.598422)
			(stroke
				(width 0.1)
				(type default)
			)
			(layer "F.Fab")
		)
		(fp_line
			(start -0.500126 -0.201422)
			(end 0.500126 -0.201422)
			(stroke
				(width 0.1)
				(type default)
			)
			(layer "F.Fab")
		)
		(fp_line
			(start 0.500126 1.598422)
			(end -0.500126 1.598422)
			(stroke
				(width 0.1)
				(type default)
			)
			(layer "F.Fab")
		)
		(fp_line
			(start -0.500126 1.598422)
			(end -0.500126 -0.201422)
			(stroke
				(width 0.1)
				(type default)
			)
			(layer "F.Fab")
		)
		(pad "1" smd rect
			(at 0 0)
			(size 0.889 0.9906)
			(layers "F.Cu" "F.Mask" "F.Paste")
			(net "PVDDQ_GHJ")
		)
		(pad "2" smd rect
			(at 0 1.397)
			(size 0.889 0.9906)
			(layers "F.Cu" "F.Mask" "F.Paste")
			(net "GND")
		)
		(zone
			(layer "F.Cu")
			(hatch none 0.5)
			(connect_pads
				(clearance 0)
			)
			(min_thickness 0.25)
			(keepout
				(tracks allowed)
				(vias not_allowed)
				(pads allowed)
				(copperpour not_allowed)
				(footprints allowed)
			)
			(placement
				(enabled no)
				(sheetname "")
			)
			(fill
				(thermal_gap 0.5)
				(thermal_bridge_width 0.5)
				(island_removal_mode 0)
			)
			(polygon
				(pts
					(xy 102.3493 -2.8575) (xy 102.3493 -3.8481) (xy 101.8413 -3.8481) (xy 101.8413 -2.8575)
				)
			)
		)
		(zone
			(layer "F.Cu")
			(hatch none 0.5)
			(connect_pads
				(clearance 0)
			)
			(min_thickness 0.25)
			(keepout
				(tracks not_allowed)
				(vias allowed)
				(pads allowed)
				(copperpour not_allowed)
				(footprints allowed)
			)
			(placement
				(enabled no)
				(sheetname "")
			)
			(fill
				(thermal_gap 0.5)
				(thermal_bridge_width 0.5)
				(island_removal_mode 0)
			)
			(polygon
				(pts
					(xy 102.3493 -2.8575) (xy 102.3493 -3.8481) (xy 101.8413 -3.8481) (xy 101.8413 -2.8575)
				)
			)
		)
	)
	(footprint ""
		(layer "F.Cu")
		(at 194.7545 -59.817 -90)
		(property "Reference" "C4E19"
			(at 0 0 270)
			(layer "F.SilkS")
			(hide yes)
			(effects
				(font
					(size 1.27 1.27)
				)
			)
		)
		(property "Value" ""
			(at 0 0 270)
			(layer "F.Fab")
			(effects
				(font
					(size 1.27 1.27)
				)
			)
		)
		(duplicate_pad_numbers_are_jumpers no)
		(fp_poly
			(pts
				(xy 0.3048 -0.1016) (xy 0.3048 0.9906) (xy -0.3048 0.9906) (xy -0.3048 -0.1016)
			)
			(stroke
				(width 0)
				(type default)
			)
			(fill no)
			(layer "F.CrtYd")
		)
		(fp_line
			(start -0.3048 0.9906)
			(end 0.3048 0.9906)
			(stroke
				(width 0.1)
				(type default)
			)
			(layer "F.Fab")
		)
		(fp_line
			(start 0.3048 0.9906)
			(end 0.3048 -0.1016)
			(stroke
				(width 0.1)
				(type default)
			)
			(layer "F.Fab")
		)
		(fp_line
			(start -0.3048 -0.1016)
			(end -0.3048 0.9906)
			(stroke
				(width 0.1)
				(type default)
			)
			(layer "F.Fab")
		)
		(fp_line
			(start 0.3048 -0.1016)
			(end -0.3048 -0.1016)
			(stroke
				(width 0.1)
				(type default)
			)
			(layer "F.Fab")
		)
		(pad "1" smd rect
			(at 0 0 270)
			(size 0.508 0.508)
			(layers "F.Cu" "F.Mask" "F.Paste")
			(net "VR_FET_SW_P12V_STBY_PVCCIN_CPU0")
		)
		(pad "2" smd rect
			(at 0 0.889 270)
			(size 0.508 0.508)
			(layers "F.Cu" "F.Mask" "F.Paste")
			(net "GND")
		)
		(zone
			(layer "F.Cu")
			(hatch none 0.5)
			(connect_pads
				(clearance 0)
			)
			(min_thickness 0.25)
			(keepout
				(tracks not_allowed)
				(vias allowed)
				(pads allowed)
				(copperpour not_allowed)
				(footprints allowed)
			)
			(placement
				(enabled no)
				(sheetname "")
			)
			(fill
				(thermal_gap 0.5)
				(thermal_bridge_width 0.5)
				(island_removal_mode 0)
			)
			(polygon
				(pts
					(xy 194.1195 -60.071) (xy 194.1195 -59.563) (xy 194.5005 -59.563) (xy 194.5005 -60.071)
				)
			)
		)
		(zone
			(layer "F.Cu")
			(hatch none 0.5)
			(connect_pads
				(clearance 0)
			)
			(min_thickness 0.25)
			(keepout
				(tracks allowed)
				(vias not_allowed)
				(pads allowed)
				(copperpour not_allowed)
				(footprints allowed)
			)
			(placement
				(enabled no)
				(sheetname "")
			)
			(fill
				(thermal_gap 0.5)
				(thermal_bridge_width 0.5)
				(island_removal_mode 0)
			)
			(polygon
				(pts
					(xy 194.5005 -60.071) (xy 194.5005 -59.563) (xy 194.1195 -59.563) (xy 194.1195 -60.071)
				)
			)
		)
	)
	(footprint ""
		(layer "F.Cu")
		(at 11.249914 -45.310044 -90)
		(property "Reference" "RM1E1"
			(at 1.495044 -4.651756 90)
			(unlocked yes)
			(layer "F.SilkS")
			(effects
				(font
					(size 0.7874 0.5842)
					(thickness 0.1524)
				)
				(justify left)
			)
		)
		(property "Value" ""
			(at 0 0 270)
			(layer "F.Fab")
			(effects
				(font
					(size 1.27 1.27)
				)
			)
		)
		(duplicate_pad_numbers_are_jumpers no)
		(fp_line
			(start -3.549904 17.223994)
			(end -3.549904 -3.929888)
			(stroke
				(width 0.1524)
				(type default)
			)
			(layer "F.SilkS")
		)
		(fp_line
			(start -3.549904 -3.929888)
			(end 3.549904 -3.929888)
			(stroke
				(width 0.1524)
				(type default)
			)
			(layer "F.SilkS")
		)
		(fp_line
			(start 3.549904 -3.929888)
			(end 3.549904 17.202912)
			(stroke
				(width 0.1524)
				(type default)
			)
			(layer "F.SilkS")
		)
		(fp_poly
			(pts
				(xy 4.863084 -2.237486) (xy 3.593084 -2.745486) (xy 4.863084 -3.253486)
			)
			(stroke
				(width 0)
				(type default)
			)
			(fill yes)
			(layer "F.SilkS")
		)
		(fp_poly
			(pts
				(xy 5.80644 0.05715) (xy 4.53644 -0.45085) (xy 5.80644 -0.95885)
			)
			(stroke
				(width 0)
				(type default)
			)
			(fill yes)
			(layer "B.SilkS")
		)
		(fp_poly
			(pts
				(xy -3.549904 -3.929888) (xy 3.549904 -3.929888) (xy 3.549904 20.7899) (xy 1.599946 20.7899) (xy 1.599946 42.489882)
				(xy -1.599946 42.489882) (xy -1.599946 20.7899) (xy -3.549904 20.7899)
			)
			(stroke
				(width 0)
				(type default)
			)
			(fill no)
			(layer "F.CrtYd")
		)
		(fp_poly
			(pts
				(xy 6.134608 0.049022) (xy 4.864608 -0.458978) (xy 6.134608 -0.966978)
			)
			(stroke
				(width 0)
				(type default)
			)
			(fill yes)
			(layer "B.Fab")
		)
		(fp_line
			(start -1.599946 42.489882)
			(end -1.599946 20.7899)
			(stroke
				(width 0.1)
				(type default)
			)
			(layer "F.Fab")
		)
		(fp_line
			(start 1.599946 42.489882)
			(end -1.599946 42.489882)
			(stroke
				(width 0.1)
				(type default)
			)
			(layer "F.Fab")
		)
		(fp_line
			(start -3.549904 20.7899)
			(end -3.549904 -3.929888)
			(stroke
				(width 0.1)
				(type default)
			)
			(layer "F.Fab")
		)
		(fp_line
			(start -1.599946 20.7899)
			(end -3.549904 20.7899)
			(stroke
				(width 0.1)
				(type default)
			)
			(layer "F.Fab")
		)
		(fp_line
			(start 1.599946 20.7899)
			(end 1.599946 42.489882)
			(stroke
				(width 0.1)
				(type default)
			)
			(layer "F.Fab")
		)
		(fp_line
			(start 3.549904 20.7899)
			(end 1.599946 20.7899)
			(stroke
				(width 0.1)
				(type default)
			)
			(layer "F.Fab")
		)
		(fp_line
			(start -3.549904 -3.929888)
			(end 3.549904 -3.929888)
			(stroke
				(width 0.1)
				(type default)
			)
			(layer "F.Fab")
		)
		(fp_line
			(start 3.549904 -3.929888)
			(end 3.549904 20.7899)
			(stroke
				(width 0.1)
				(type default)
			)
			(layer "F.Fab")
		)
		(fp_poly
			(pts
				(xy 6.134608 0.051054) (xy 4.864608 -0.456946) (xy 6.134608 -0.964946)
			)
			(stroke
				(width 0)
				(type default)
			)
			(fill yes)
			(layer "F.Fab")
		)
		(fp_text user "2"
			(at -4.34721 -1.956308 0)
			(unlocked yes)
			(layer "F.SilkS")
			(effects
				(font
					(size 0.7874 0.5842)
					(thickness 0.1524)
				)
				(justify left)
			)
		)
		(fp_text user "3"
			(at -4.120642 -3.068066 0)
			(unlocked yes)
			(layer "F.SilkS")
			(effects
				(font
					(size 0.7874 0.5842)
					(thickness 0.1524)
				)
				(justify left)
			)
		)
		(fp_text user "2"
			(at 2.892044 11.624564 270)
			(unlocked yes)
			(layer "B.Fab")
			(effects
				(font
					(size 0.635 0.635)
					(thickness 0.1524)
				)
				(justify left mirror)
			)
		)
		(fp_text user "3"
			(at -2.518156 6.747764 270)
			(unlocked yes)
			(layer "B.Fab")
			(effects
				(font
					(size 0.635 0.635)
					(thickness 0.1524)
				)
				(justify left mirror)
			)
		)
		(fp_text user "2"
			(at 2.257044 11.624564 270)
			(unlocked yes)
			(layer "F.Fab")
			(effects
				(font
					(size 0.635 0.635)
					(thickness 0.1524)
				)
				(justify left)
			)
		)
		(fp_text user "3"
			(at -2.848356 6.722364 270)
			(unlocked yes)
			(layer "F.Fab")
			(effects
				(font
					(size 0.635 0.635)
					(thickness 0.1524)
				)
				(justify left)
			)
		)
		(pad "1" thru_hole rect
			(at 0 0 270)
			(size 3.556 3.556)
			(drill 3.175)
			(layers "*.Cu" "*.Mask")
			(remove_unused_layers no)
			(net "GND")
			(clearance 0.127)
			(thermal_gap 0.127)
			(padstack
				(mode front_inner_back)
				(layer "Inner"
					(shape circle)
					(size 3.556 3.556)
					(clearance 0.127)
				)
				(layer "B.Cu"
					(shape rect)
					(size 3.556 3.556)
					(clearance 0.127)
				)
			)
		)
		(pad "2" thru_hole circle
			(at 0 11.75004 270)
			(size 3.556 3.556)
			(drill 3.175)
			(layers "*.Cu" "*.Mask")
			(remove_unused_layers no)
			(net "GND")
			(clearance 0.127)
			(thermal_gap 0.127)
		)
		(pad "3" thru_hole circle
			(at 0 6.620002 270)
			(size 3.556 3.556)
			(drill 3.175)
			(layers "*.Cu" "*.Mask")
			(remove_unused_layers no)
			(net "GND")
			(clearance 0.127)
			(thermal_gap 0.127)
		)
	)
	(footprint ""
		(layer "F.Cu")
		(at 324.5485 -121.666 90)
		(property "Reference" "C6B9"
			(at -0.8382 -0.67818 90)
			(unlocked yes)
			(layer "F.SilkS")
			(effects
				(font
					(size 0.4064 0.254)
					(thickness 0.1524)
				)
				(justify left)
			)
		)
		(property "Value" ""
			(at 0 0 90)
			(layer "F.Fab")
			(effects
				(font
					(size 1.27 1.27)
				)
			)
		)
		(duplicate_pad_numbers_are_jumpers no)
		(fp_poly
			(pts
				(xy 0.3048 -0.1016) (xy 0.3048 0.9906) (xy -0.3048 0.9906) (xy -0.3048 -0.1016)
			)
			(stroke
				(width 0)
				(type default)
			)
			(fill no)
			(layer "F.CrtYd")
		)
		(fp_line
			(start 0.3048 -0.1016)
			(end -0.3048 -0.1016)
			(stroke
				(width 0.1)
				(type default)
			)
			(layer "F.Fab")
		)
		(fp_line
			(start -0.3048 -0.1016)
			(end -0.3048 0.9906)
			(stroke
				(width 0.1)
				(type default)
			)
			(layer "F.Fab")
		)
		(fp_line
			(start 0.3048 0.9906)
			(end 0.3048 -0.1016)
			(stroke
				(width 0.1)
				(type default)
			)
			(layer "F.Fab")
		)
		(fp_line
			(start -0.3048 0.9906)
			(end 0.3048 0.9906)
			(stroke
				(width 0.1)
				(type default)
			)
			(layer "F.Fab")
		)
		(pad "1" smd rect
			(at 0 0 90)
			(size 0.508 0.508)
			(layers "F.Cu" "F.Mask" "F.Paste")
			(net "P3E_CPU0_PE1_PCH_TXN<13>")
		)
		(pad "2" smd rect
			(at 0 0.889 90)
			(size 0.508 0.508)
			(layers "F.Cu" "F.Mask" "F.Paste")
			(net "P3E_CPU0_PE1_PCH_C_TXN<13>")
		)
		(zone
			(layer "F.Cu")
			(hatch none 0.5)
			(connect_pads
				(clearance 0)
			)
			(min_thickness 0.25)
			(keepout
				(tracks allowed)
				(vias not_allowed)
				(pads allowed)
				(copperpour not_allowed)
				(footprints allowed)
			)
			(placement
				(enabled no)
				(sheetname "")
			)
			(fill
				(thermal_gap 0.5)
				(thermal_bridge_width 0.5)
				(island_removal_mode 0)
			)
			(polygon
				(pts
					(xy 324.8025 -121.412) (xy 324.8025 -121.92) (xy 325.1835 -121.92) (xy 325.1835 -121.412)
				)
			)
		)
	)
	(footprint ""
		(layer "F.Cu")
		(at 185.4454 -153.416)
		(property "Reference" "R4A2"
			(at 0 0 0)
			(layer "F.SilkS")
			(hide yes)
			(effects
				(font
					(size 1.27 1.27)
				)
			)
		)
		(property "Value" ""
			(at 0 0 0)
			(layer "F.Fab")
			(effects
				(font
					(size 1.27 1.27)
				)
			)
		)
		(duplicate_pad_numbers_are_jumpers no)
		(fp_poly
			(pts
				(xy -0.2794 -0.1016) (xy 0.2794 -0.1016) (xy 0.2794 0.9906) (xy -0.2794 0.9906)
			)
			(stroke
				(width 0)
				(type default)
			)
			(fill no)
			(layer "F.CrtYd")
		)
		(fp_line
			(start -0.2794 -0.1016)
			(end -0.2794 0.9906)
			(stroke
				(width 0.1)
				(type default)
			)
			(layer "F.Fab")
		)
		(fp_line
			(start -0.2794 0.9906)
			(end 0.2794 0.9906)
			(stroke
				(width 0.1)
				(type default)
			)
			(layer "F.Fab")
		)
		(fp_line
			(start 0.2794 -0.1016)
			(end -0.2794 -0.1016)
			(stroke
				(width 0.1)
				(type default)
			)
			(layer "F.Fab")
		)
		(fp_line
			(start 0.2794 0.9906)
			(end 0.2794 -0.1016)
			(stroke
				(width 0.1)
				(type default)
			)
			(layer "F.Fab")
		)
		(pad "1" smd rect
			(at 0 0)
			(size 0.508 0.508)
			(layers "F.Cu" "F.Mask" "F.Paste")
			(net "PWRGD_PVDDQ_DEF_R")
		)
		(pad "2" smd rect
			(at 0 0.889)
			(size 0.508 0.508)
			(layers "F.Cu" "F.Mask" "F.Paste")
			(net "FM_PVTT_DEF_EN_R")
		)
		(zone
			(layer "F.Cu")
			(hatch none 0.5)
			(connect_pads
				(clearance 0)
			)
			(min_thickness 0.25)
			(keepout
				(tracks allowed)
				(vias not_allowed)
				(pads allowed)
				(copperpour not_allowed)
				(footprints allowed)
			)
			(placement
				(enabled no)
				(sheetname "")
			)
			(fill
				(thermal_gap 0.5)
				(thermal_bridge_width 0.5)
				(island_removal_mode 0)
			)
			(polygon
				(pts
					(xy 185.1914 -153.162) (xy 185.6994 -153.162) (xy 185.6994 -152.781) (xy 185.1914 -152.781)
				)
			)
		)
		(zone
			(layer "F.Cu")
			(hatch none 0.5)
			(connect_pads
				(clearance 0)
			)
			(min_thickness 0.25)
			(keepout
				(tracks not_allowed)
				(vias allowed)
				(pads allowed)
				(copperpour not_allowed)
				(footprints allowed)
			)
			(placement
				(enabled no)
				(sheetname "")
			)
			(fill
				(thermal_gap 0.5)
				(thermal_bridge_width 0.5)
				(island_removal_mode 0)
			)
			(polygon
				(pts
					(xy 185.1914 -152.781) (xy 185.6994 -152.781) (xy 185.6994 -153.162) (xy 185.1914 -153.162)
				)
			)
		)
	)
	(footprint ""
		(layer "F.Cu")
		(at 448.437 -20.2565)
		(property "Reference" "C9W10"
			(at -0.8382 -0.67818 0)
			(unlocked yes)
			(layer "F.SilkS")
			(effects
				(font
					(size 0.4064 0.254)
					(thickness 0.1524)
				)
				(justify left)
			)
		)
		(property "Value" ""
			(at 0 0 0)
			(layer "F.Fab")
			(effects
				(font
					(size 1.27 1.27)
				)
			)
		)
		(duplicate_pad_numbers_are_jumpers no)
		(fp_poly
			(pts
				(xy 0.3048 -0.1016) (xy 0.3048 0.9906) (xy -0.3048 0.9906) (xy -0.3048 -0.1016)
			)
			(stroke
				(width 0)
				(type default)
			)
			(fill no)
			(layer "F.CrtYd")
		)
		(fp_line
			(start -0.3048 -0.1016)
			(end -0.3048 0.9906)
			(stroke
				(width 0.1)
				(type default)
			)
			(layer "F.Fab")
		)
		(fp_line
			(start -0.3048 0.9906)
			(end 0.3048 0.9906)
			(stroke
				(width 0.1)
				(type default)
			)
			(layer "F.Fab")
		)
		(fp_line
			(start 0.3048 -0.1016)
			(end -0.3048 -0.1016)
			(stroke
				(width 0.1)
				(type default)
			)
			(layer "F.Fab")
		)
		(fp_line
			(start 0.3048 0.9906)
			(end 0.3048 -0.1016)
			(stroke
				(width 0.1)
				(type default)
			)
			(layer "F.Fab")
		)
		(pad "1" smd rect
			(at 0 0)
			(size 0.508 0.508)
			(layers "F.Cu" "F.Mask" "F.Paste")
			(net "PWRGD_P2V5_BMC_STBY_R")
		)
		(pad "2" smd rect
			(at 0 0.889)
			(size 0.508 0.508)
			(layers "F.Cu" "F.Mask" "F.Paste")
			(net "GND")
		)
		(zone
			(layer "F.Cu")
			(hatch none 0.5)
			(connect_pads
				(clearance 0)
			)
			(min_thickness 0.25)
			(keepout
				(tracks allowed)
				(vias not_allowed)
				(pads allowed)
				(copperpour not_allowed)
				(footprints allowed)
			)
			(placement
				(enabled no)
				(sheetname "")
			)
			(fill
				(thermal_gap 0.5)
				(thermal_bridge_width 0.5)
				(island_removal_mode 0)
			)
			(polygon
				(pts
					(xy 448.183 -20.0025) (xy 448.691 -20.0025) (xy 448.691 -19.6215) (xy 448.183 -19.6215)
				)
			)
		)
		(zone
			(layer "F.Cu")
			(hatch none 0.5)
			(connect_pads
				(clearance 0)
			)
			(min_thickness 0.25)
			(keepout
				(tracks not_allowed)
				(vias allowed)
				(pads allowed)
				(copperpour not_allowed)
				(footprints allowed)
			)
			(placement
				(enabled no)
				(sheetname "")
			)
			(fill
				(thermal_gap 0.5)
				(thermal_bridge_width 0.5)
				(island_removal_mode 0)
			)
			(polygon
				(pts
					(xy 448.183 -19.6215) (xy 448.691 -19.6215) (xy 448.691 -20.0025) (xy 448.183 -20.0025)
				)
			)
		)
	)
)
